# BASEBOARD_FAB2 (Tioga Pass) — schematic netlist excerpt (pin names and nets, part order shuffled) for the footprints in the layout excerpt that follows; sources: Cadence DE-HDL packaged netlist, KiCad conversion of Wiwynn_Tioga_Pass_MB.brd

J4G2  SCONN288_H44441004  SCONN  pkg PIP  page 45
  \12v\(1)  = P12V_NVDIMM_ABC
  VSS(93)  = GND
  DQ(4)  = M_B_DQ<5>
  VSS(92)  = GND
  DQ(0)  = M_B_DQ<1>
  VSS(91)  = GND
  DQS9P  = M_B_DQS_DP<9>
  DQS9N  = M_B_DQS_DN<9>
  VSS(90)  = GND
  DQ(6)  = M_B_DQ<7>
  VSS(89)  = GND
  DQ(2)  = M_B_DQ<3>
  VSS(88)  = GND
  DQ(12)  = M_B_DQ<13>
  VSS(87)  = GND
  DQ(8)  = M_B_DQ<9>
  VSS(86)  = GND
  DQS10P  = M_B_DQS_DP<10>
  DQS10N  = M_B_DQS_DN<10>
  VSS(85)  = GND
  DQ(14)  = M_B_DQ<15>
  VSS(84)  = GND
  DQ(10)  = M_B_DQ<11>
  VSS(83)  = GND
  DQ(20)  = M_B_DQ<21>
  VSS(82)  = GND
  DQ(16)  = M_B_DQ<17>
  VSS(81)  = GND
  DQS11P  = M_B_DQS_DP<11>
  DQS11N  = M_B_DQS_DN<11>
  VSS(80)  = GND
  DQ(22)  = M_B_DQ<23>
  VSS(79)  = GND
  DQ(18)  = M_B_DQ<19>
  VSS(78)  = GND
  DQ(28)  = M_B_DQ<29>
  VSS(77)  = GND
  DQ(24)  = M_B_DQ<25>
  VSS(76)  = GND
  DQS12P  = M_B_DQS_DP<12>
  DQS12N  = M_B_DQS_DN<12>
  VSS(75)  = GND
  DQ(30)  = M_B_DQ<31>
  VSS(74)  = GND
  DQ(26)  = M_B_DQ<27>
  VSS(73)  = GND
  CB(4)  = M_B_ECC<5>
  VSS(72)  = GND
  CB(0)  = M_B_ECC<1>
  VSS(71)  = GND
  DQS17P  = M_B_DQS_DP<17>
  DQS17N  = M_B_DQS_DN<17>
  VSS(70)  = GND
  CB(6)  = M_B_ECC<7>
  VSS(69)  = GND
  CB(2)  = M_B_ECC<3>
  VSS(68)  = GND
  RESET_N  = M_ABC_RST_N
  VDD(25)  = PVDDQ_ABC
  CKE(0)  = M_B_CKE<0>
  VDD(24)  = PVDDQ_ABC
  ACT_N  = M_B_ACT_N
  BG(0)  = M_B_BG<0>
  VDD(23)  = PVDDQ_ABC
  A12  = M_B_MA<12>
  A9  = M_B_MA<9>
  VDD(22)  = PVDDQ_ABC
  A8  = M_B_MA<8>
  A6  = M_B_MA<6>
  VDD(21)  = PVDDQ_ABC
  A3  = M_B_MA<3>
  A1  = M_B_MA<1>
  VDD(20)  = PVDDQ_ABC
  CK0P  = M_B_CLK_DP<0>
  CK0N  = M_B_CLK_DN<0>
  VDD(19)  = PVDDQ_ABC
  VTT(1)  = PVTT_ABC
  EVENT_N  = FM_DIMM_EVENT_COD_N
  A0  = M_B_MA<0>
  VDD(18)  = PVDDQ_ABC
  BA(0)  = M_B_BA<0>
  A16_RAS_N  = M_B_MA<16>
  VDD(17)  = PVDDQ_ABC
  S0_N  = M_B_CS_N<0>
  VDD(16)  = PVDDQ_ABC
  A15_CAS_N  = M_B_MA<15>
  ODT(0)  = M_B_ODT<0>
  VDD(15)  = PVDDQ_ABC
  S1_N  = M_B_CS_N<1>
  VDD(14)  = PVDDQ_ABC
  ODT(1)  = M_B_ODT<1>
  VDD(13)  = PVDDQ_ABC
  S2_N_C(0)  = M_B_CS_N<2>
  VSS(67)  = GND
  DQ(36)  = M_B_DQ<37>
  VSS(66)  = GND
  DQ(32)  = M_B_DQ<33>
  VSS(65)  = GND
  DQS13P  = M_B_DQS_DP<13>
  DQS13N  = M_B_DQS_DN<13>
  VSS(64)  = GND
  DQ(38)  = M_B_DQ<39>
  VSS(63)  = GND
  DQ(34)  = M_B_DQ<35>
  VSS(62)  = GND
  DQ(44)  = M_B_DQ<45>
  VSS(61)  = GND
  DQ(40)  = M_B_DQ<41>
  VSS(60)  = GND
  DQS14P  = M_B_DQS_DP<14>
  DQS14N  = M_B_DQS_DN<14>
  VSS(59)  = GND
  DQ(46)  = M_B_DQ<47>
  VSS(58)  = GND
  DQ(42)  = M_B_DQ<43>
  VSS(57)  = GND
  DQ(52)  = M_B_DQ<53>
  VSS(56)  = GND
  DQ(48)  = M_B_DQ<49>
  VSS(55)  = GND
  DQS15P  = M_B_DQS_DP<15>
  DQS15N  = M_B_DQS_DN<15>
  VSS(54)  = GND
  DQ(54)  = M_B_DQ<55>
  VSS(53)  = GND
  DQ(50)  = M_B_DQ<51>
  VSS(52)  = GND
  DQ(60)  = M_B_DQ<61>
  VSS(51)  = GND
  DQ(56)  = M_B_DQ<57>
  VSS(50)  = GND
  DQS16P  = M_B_DQS_DP<16>
  DQS16N  = M_B_DQS_DN<16>
  VSS(49)  = GND
  DQ(62)  = M_B_DQ<63>
  VSS(48)  = GND
  DQ(58)  = M_B_DQ<59>
  VSS(47)  = GND
  SA(0)  = GND
  SA(1)  = PVPP_ABC
  SCL  = SMB_DDR_ABC_VPP_SCL
  VPP(4)  = PVPP_ABC
  VPP(3)  = PVPP_ABC
  RFU(2)  = TP_CH_B_DIMM_B0_RFU_2
  \12v\(0)  = P12V_NVDIMM_ABC
  VREFCA  = M_B_VREF
  VSS(46)  = GND
  DQ(5)  = M_B_DQ<4>
  VSS(45)  = GND
  DQ(1)  = M_B_DQ<0>
  VSS(44)  = GND
  DQS0N  = M_B_DQS_DN<0>
  DQS0P  = M_B_DQS_DP<0>
  VSS(43)  = GND
  DQ(7)  = M_B_DQ<6>
  VSS(42)  = GND
  DQ(3)  = M_B_DQ<2>
  VSS(41)  = GND
  DQ(13)  = M_B_DQ<12>
  VSS(40)  = GND
  DQ(9)  = M_B_DQ<8>
  VSS(39)  = GND
  DQS1N  = M_B_DQS_DN<1>
  DQS1P  = M_B_DQS_DP<1>
  VSS(38)  = GND
  DQ(15)  = M_B_DQ<14>
  VSS(37)  = GND
  DQ(11)  = M_B_DQ<10>
  VSS(36)  = GND
  DQ(21)  = M_B_DQ<20>
  VSS(35)  = GND
  DQ(17)  = M_B_DQ<16>
  VSS(34)  = GND
  DQS2N  = M_B_DQS_DN<2>
  DQS2P  = M_B_DQS_DP<2>
  VSS(33)  = GND
  DQ(23)  = M_B_DQ<22>
  VSS(32)  = GND
  DQ(19)  = M_B_DQ<18>
  VSS(31)  = GND
  DQ(29)  = M_B_DQ<28>
  VSS(30)  = GND
  DQ(25)  = M_B_DQ<24>
  VSS(29)  = GND
  DQS3N  = M_B_DQS_DN<3>
  DQS3P  = M_B_DQS_DP<3>
  VSS(28)  = GND
  DQ(31)  = M_B_DQ<30>
  VSS(27)  = GND
  DQ(27)  = M_B_DQ<26>
  VSS(26)  = GND
  CB(5)  = M_B_ECC<4>
  VSS(25)  = GND
  CB(1)  = M_B_ECC<0>
  VSS(24)  = GND
  DQS8N  = M_B_DQS_DN<8>
  DQS8P  = M_B_DQS_DP<8>
  VSS(23)  = GND
  CB(7)  = M_B_ECC<6>
  VSS(22)  = GND
  CB(3)  = M_B_ECC<2>
  VSS(21)  = GND
  CKE(1)  = M_B_CKE<1>
  VDD(12)  = PVDDQ_ABC
  RFU(0)  = TP_CH_B_DIMM_B0_RFU_0
  VDD(11)  = PVDDQ_ABC
  BG(1)  = M_B_BG<1>
  ALERT_N  = M_B_ALERT_N
  VDD(10)  = PVDDQ_ABC
  A11  = M_B_MA<11>
  A7  = M_B_MA<7>
  VDD(9)  = PVDDQ_ABC
  A5  = M_B_MA<5>
  A4  = M_B_MA<4>
  VDD(8)  = PVDDQ_ABC
  A2  = M_B_MA<2>
  VDD(7)  = PVDDQ_ABC
  CK1P  = M_B_CLK_DP<1>
  CK1N  = M_B_CLK_DN<1>
  VDD(6)  = PVDDQ_ABC
  VTT(0)  = PVTT_ABC
  PAR  = M_B_PAR
  VDD(5)  = PVDDQ_ABC
  BA(1)  = M_B_BA<1>
  A10  = M_B_MA<10>
  VDD(4)  = PVDDQ_ABC
  RFU(1)  = TP_CH_B_DIMM_B0_RFU_1
  A14_WE_N  = M_B_MA<14>
  VDD(3)  = PVDDQ_ABC
  SAVE_N_NC  = FM_ADR_COMPLETE_ABC_N
  VDD(2)  = PVDDQ_ABC
  A13  = M_B_MA<13>
  VDD(1)  = PVDDQ_ABC
  A17  = M_B_MA<17>
  C(2)  = M_B_C<2>
  VDD(0)  = PVDDQ_ABC
  S3_N_C(1)  = M_B_CS_N<3>
  SA(2)  = GND
  VSS(20)  = GND
  DQ(37)  = M_B_DQ<36>
  VSS(19)  = GND
  DQ(33)  = M_B_DQ<32>
  VSS(18)  = GND
  DQS4N  = M_B_DQS_DN<4>
  DQS4P  = M_B_DQS_DP<4>
  VSS(17)  = GND
  DQ(39)  = M_B_DQ<38>
  VSS(16)  = GND
  DQ(35)  = M_B_DQ<34>
  VSS(15)  = GND
  DQ(45)  = M_B_DQ<44>
  VSS(14)  = GND
  DQ(41)  = M_B_DQ<40>
  VSS(13)  = GND
  DQS5N  = M_B_DQS_DN<5>
  DQS5P  = M_B_DQS_DP<5>
  VSS(12)  = GND
  DQ(47)  = M_B_DQ<46>
  VSS(11)  = GND
  DQ(43)  = M_B_DQ<42>
  VSS(10)  = GND
  DQ(53)  = M_B_DQ<52>
  VSS(9)  = GND
  DQ(49)  = M_B_DQ<48>
  VSS(8)  = GND
  DQS6N  = M_B_DQS_DN<6>
  DQS6P  = M_B_DQS_DP<6>
  VSS(7)  = GND
  DQ(55)  = M_B_DQ<54>
  VSS(6)  = GND
  DQ(51)  = M_B_DQ<50>
  VSS(5)  = GND
  DQ(61)  = M_B_DQ<60>
  VSS(4)  = GND
  DQ(57)  = M_B_DQ<56>
  VSS(3)  = GND
  DQS7N  = M_B_DQS_DN<7>
  DQS7P  = M_B_DQS_DP<7>
  VSS(2)  = GND
  DQ(63)  = M_B_DQ<62>
  VSS(1)  = GND
  DQ(59)  = M_B_DQ<58>
  VSS(0)  = GND
  VDDSPD  = PVPP_ABC
  SDA  = SMB_DDR_ABC_VPP_SDA
  VPP(1)  = PVPP_ABC
  VPP(0)  = PVPP_ABC
  VPP(2)  = PVPP_ABC

(kicad_pcb
	(version 20260206)
	(generator "pcbnew")
	(generator_version "10.0")
	(general
		(thickness 1.6)
		(legacy_teardrops no)
	)
	(paper "A4")
	(title_block
		(title "Wiwynn_Tioga_Pass_MB.brd")
		(comment 1 "Tioga Pass / footprint 1899 of 4770 (J4G2), pads 203-251 of 291")
	)
	(layers
		(0 "F.Cu" signal "TOP")
		(4 "In1.Cu" signal "L2GND")
		(6 "In2.Cu" signal "L3")
		(8 "In3.Cu" signal "L4GND")
		(10 "In4.Cu" signal "L5")
		(12 "In5.Cu" signal "L6GND")
		(14 "In6.Cu" signal "L7VCC")
		(16 "In7.Cu" signal "L8VCC")
		(18 "In8.Cu" signal "L9GND")
		(20 "In9.Cu" signal "L10")
		(22 "In10.Cu" signal "L11GND")
		(24 "In11.Cu" signal "L12")
		(26 "In12.Cu" signal "L13GND")
		(2 "B.Cu" signal "BOTTOM")
		(9 "F.Adhes" user "F.Adhesive")
		(11 "B.Adhes" user "B.Adhesive")
		(13 "F.Paste" user "Package Geometry/Pastemask Top")
		(15 "B.Paste" user "Package Geometry/Pastemask Bottom")
		(5 "F.SilkS" user "Ref Des/Silkscreen Top")
		(7 "B.SilkS" user "Ref Des/Silkscreen Bottom")
		(1 "F.Mask" user "Board Geometry/Soldermask Top")
		(3 "B.Mask" user "Board Geometry/Soldermask Bottom")
		(17 "Dwgs.User" user "User.Drawings")
		(19 "Cmts.User" user "User.Comments")
		(21 "Eco1.User" user "User.Eco1")
		(23 "Eco2.User" user "User.Eco2")
		(25 "Edge.Cuts" user "Board Geometry/Outline")
		(27 "Margin" user)
		(31 "F.CrtYd" user "Package Geometry/Place Bound Top")
		(29 "B.CrtYd" user "Package Geometry/Place Bound Bottom")
		(35 "F.Fab" user "Ref Des/Assembly Top")
		(33 "B.Fab" user "Ref Des/Assembly Bottom")
	)
	(footprint ""
		(layer "F.Cu")
		(at 194.700398 -5.822442 90)
		(property "Reference" "J4G2"
			(at 6.596888 37.58311 0)
			(unlocked yes)
			(layer "F.SilkS")
			(effects
				(font
					(size 0.7874 0.5842)
					(thickness 0.1524)
				)
				(justify left)
			)
		)
		(property "Value" ""
			(at 0 0 90)
			(layer "F.Fab")
			(effects
				(font
					(size 1.27 1.27)
				)
			)
		)
		(duplicate_pad_numbers_are_jumpers no)
		(pad "200" smd rect
			(at 4.59994 46.74997 90)
			(size 1.8034 0.508)
			(layers "F.Cu" "F.Mask" "F.Paste")
			(net "GND")
		)
		(pad "201" smd rect
			(at 4.59994 47.600108 90)
			(size 1.8034 0.508)
			(layers "F.Cu" "F.Mask" "F.Paste")
			(net "M_B_ECC<2>")
		)
		(pad "202" smd rect
			(at 4.59994 48.449992 90)
			(size 1.8034 0.508)
			(layers "F.Cu" "F.Mask" "F.Paste")
			(net "GND")
		)
		(pad "203" smd rect
			(at 4.59994 49.299876 90)
			(size 1.8034 0.508)
			(layers "F.Cu" "F.Mask" "F.Paste")
			(net "M_B_CKE<1>")
		)
		(pad "204" smd rect
			(at 4.59994 50.150014 90)
			(size 1.8034 0.508)
			(layers "F.Cu" "F.Mask" "F.Paste")
			(net "PVDDQ_ABC")
		)
		(pad "205" smd rect
			(at 4.59994 50.999898 90)
			(size 1.8034 0.508)
			(layers "F.Cu" "F.Mask" "F.Paste")
			(net "TP_CH_B_DIMM_B0_RFU_0")
		)
		(pad "206" smd rect
			(at 4.59994 51.850036 90)
			(size 1.8034 0.508)
			(layers "F.Cu" "F.Mask" "F.Paste")
			(net "PVDDQ_ABC")
		)
		(pad "207" smd rect
			(at 4.59994 52.69992 90)
			(size 1.8034 0.508)
			(layers "F.Cu" "F.Mask" "F.Paste")
			(net "M_B_BG<1>")
		)
		(pad "208" smd rect
			(at 4.59994 53.550058 90)
			(size 1.8034 0.508)
			(layers "F.Cu" "F.Mask" "F.Paste")
			(net "M_B_ALERT_N")
		)
		(pad "209" smd rect
			(at 4.59994 54.399942 90)
			(size 1.8034 0.508)
			(layers "F.Cu" "F.Mask" "F.Paste")
			(net "PVDDQ_ABC")
		)
		(pad "210" smd rect
			(at 4.59994 55.25008 90)
			(size 1.8034 0.508)
			(layers "F.Cu" "F.Mask" "F.Paste")
			(net "M_B_MA<11>")
		)
		(pad "211" smd rect
			(at 4.59994 56.099964 90)
			(size 1.8034 0.508)
			(layers "F.Cu" "F.Mask" "F.Paste")
			(net "M_B_MA<7>")
		)
		(pad "212" smd rect
			(at 4.59994 56.950102 90)
			(size 1.8034 0.508)
			(layers "F.Cu" "F.Mask" "F.Paste")
			(net "PVDDQ_ABC")
		)
		(pad "213" smd rect
			(at 4.59994 57.799986 90)
			(size 1.8034 0.508)
			(layers "F.Cu" "F.Mask" "F.Paste")
			(net "M_B_MA<5>")
		)
		(pad "214" smd rect
			(at 4.59994 58.650124 90)
			(size 1.8034 0.508)
			(layers "F.Cu" "F.Mask" "F.Paste")
			(net "M_B_MA<4>")
		)
		(pad "215" smd rect
			(at 4.59994 59.500008 90)
			(size 1.8034 0.508)
			(layers "F.Cu" "F.Mask" "F.Paste")
			(net "PVDDQ_ABC")
		)
		(pad "216" smd rect
			(at 4.59994 60.349892 90)
			(size 1.8034 0.508)
			(layers "F.Cu" "F.Mask" "F.Paste")
			(net "M_B_MA<2>")
		)
		(pad "217" smd rect
			(at 4.59994 61.20003 90)
			(size 1.8034 0.508)
			(layers "F.Cu" "F.Mask" "F.Paste")
			(net "PVDDQ_ABC")
		)
		(pad "218" smd rect
			(at 4.59994 62.049914 90)
			(size 1.8034 0.508)
			(layers "F.Cu" "F.Mask" "F.Paste")
			(net "M_B_CLK_DP<1>")
		)
		(pad "219" smd rect
			(at 4.59994 62.900052 90)
			(size 1.8034 0.508)
			(layers "F.Cu" "F.Mask" "F.Paste")
			(net "M_B_CLK_DN<1>")
		)
		(pad "220" smd rect
			(at 4.59994 63.749936 90)
			(size 1.8034 0.508)
			(layers "F.Cu" "F.Mask" "F.Paste")
			(net "PVDDQ_ABC")
		)
		(pad "221" smd rect
			(at 4.59994 64.600074 90)
			(size 1.8034 0.508)
			(layers "F.Cu" "F.Mask" "F.Paste")
			(net "PVTT_ABC")
		)
		(pad "222" smd rect
			(at 4.59994 70.550024 90)
			(size 1.8034 0.508)
			(layers "F.Cu" "F.Mask" "F.Paste")
			(net "M_B_PAR")
		)
		(pad "223" smd rect
			(at 4.59994 71.399908 90)
			(size 1.8034 0.508)
			(layers "F.Cu" "F.Mask" "F.Paste")
			(net "PVDDQ_ABC")
		)
		(pad "224" smd rect
			(at 4.59994 72.250046 90)
			(size 1.8034 0.508)
			(layers "F.Cu" "F.Mask" "F.Paste")
			(net "M_B_BA<1>")
		)
		(pad "225" smd rect
			(at 4.59994 73.09993 90)
			(size 1.8034 0.508)
			(layers "F.Cu" "F.Mask" "F.Paste")
			(net "M_B_MA<10>")
		)
		(pad "226" smd rect
			(at 4.59994 73.950068 90)
			(size 1.8034 0.508)
			(layers "F.Cu" "F.Mask" "F.Paste")
			(net "PVDDQ_ABC")
		)
		(pad "227" smd rect
			(at 4.59994 74.799952 90)
			(size 1.8034 0.508)
			(layers "F.Cu" "F.Mask" "F.Paste")
			(net "TP_CH_B_DIMM_B0_RFU_1")
		)
		(pad "228" smd rect
			(at 4.59994 75.65009 90)
			(size 1.8034 0.508)
			(layers "F.Cu" "F.Mask" "F.Paste")
			(net "M_B_MA<14>")
		)
		(pad "229" smd rect
			(at 4.59994 76.499974 90)
			(size 1.8034 0.508)
			(layers "F.Cu" "F.Mask" "F.Paste")
			(net "PVDDQ_ABC")
		)
		(pad "230" smd rect
			(at 4.59994 77.350112 90)
			(size 1.8034 0.508)
			(layers "F.Cu" "F.Mask" "F.Paste")
			(net "FM_ADR_COMPLETE_ABC_N")
		)
		(pad "231" smd rect
			(at 4.59994 78.199996 90)
			(size 1.8034 0.508)
			(layers "F.Cu" "F.Mask" "F.Paste")
			(net "PVDDQ_ABC")
		)
		(pad "232" smd rect
			(at 4.59994 79.04988 90)
			(size 1.8034 0.508)
			(layers "F.Cu" "F.Mask" "F.Paste")
			(net "M_B_MA<13>")
		)
		(pad "233" smd rect
			(at 4.59994 79.900018 90)
			(size 1.8034 0.508)
			(layers "F.Cu" "F.Mask" "F.Paste")
			(net "PVDDQ_ABC")
		)
		(pad "234" smd rect
			(at 4.59994 80.749902 90)
			(size 1.8034 0.508)
			(layers "F.Cu" "F.Mask" "F.Paste")
			(net "M_B_MA<17>")
		)
		(pad "235" smd rect
			(at 4.59994 81.60004 90)
			(size 1.8034 0.508)
			(layers "F.Cu" "F.Mask" "F.Paste")
			(net "M_B_C<2>")
		)
		(pad "236" smd rect
			(at 4.59994 82.449924 90)
			(size 1.8034 0.508)
			(layers "F.Cu" "F.Mask" "F.Paste")
			(net "PVDDQ_ABC")
		)
		(pad "237" smd rect
			(at 4.59994 83.300062 90)
			(size 1.8034 0.508)
			(layers "F.Cu" "F.Mask" "F.Paste")
			(net "M_B_CS_N<3>")
		)
		(pad "238" smd rect
			(at 4.59994 84.149946 90)
			(size 1.8034 0.508)
			(layers "F.Cu" "F.Mask" "F.Paste")
			(net "GND")
		)
		(pad "239" smd rect
			(at 4.59994 85.000084 90)
			(size 1.8034 0.508)
			(layers "F.Cu" "F.Mask" "F.Paste")
			(net "GND")
		)
		(pad "240" smd rect
			(at 4.59994 85.849968 90)
			(size 1.8034 0.508)
			(layers "F.Cu" "F.Mask" "F.Paste")
			(net "M_B_DQ<36>")
		)
		(pad "241" smd rect
			(at 4.59994 86.700106 90)
			(size 1.8034 0.508)
			(layers "F.Cu" "F.Mask" "F.Paste")
			(net "GND")
		)
		(pad "242" smd rect
			(at 4.59994 87.54999 90)
			(size 1.8034 0.508)
			(layers "F.Cu" "F.Mask" "F.Paste")
			(net "M_B_DQ<32>")
		)
		(pad "243" smd rect
			(at 4.59994 88.399874 90)
			(size 1.8034 0.508)
			(layers "F.Cu" "F.Mask" "F.Paste")
			(net "GND")
		)
		(pad "244" smd rect
			(at 4.59994 89.250012 90)
			(size 1.8034 0.508)
			(layers "F.Cu" "F.Mask" "F.Paste")
			(net "M_B_DQS_DN<4>")
		)
		(pad "245" smd rect
			(at 4.59994 90.099896 90)
			(size 1.8034 0.508)
			(layers "F.Cu" "F.Mask" "F.Paste")
			(net "M_B_DQS_DP<4>")
		)
		(pad "246" smd rect
			(at 4.59994 90.950034 90)
			(size 1.8034 0.508)
			(layers "F.Cu" "F.Mask" "F.Paste")
			(net "GND")
		)
		(pad "247" smd rect
			(at 4.59994 91.799918 90)
			(size 1.8034 0.508)
			(layers "F.Cu" "F.Mask" "F.Paste")
			(net "M_B_DQ<38>")
		)
		(pad "248" smd rect
			(at 4.59994 92.650056 90)
			(size 1.8034 0.508)
			(layers "F.Cu" "F.Mask" "F.Paste")
			(net "GND")
		)
	)
)
